# T6G (Grand Teton) — schematic netlist excerpt (pin names and nets, part order shuffled) for the footprints in the layout excerpt that follows; sources: Cadence DE-HDL packaged netlist, KiCad conversion of 04192023_DAF0TMB3IC0_F0TG_MB_C_brd_V02_OCP.brd

C2359  Q_CAP  22UF 4V 20% X6S  pkg C0402  page 73 : A = PVDDCR_CPU1_P1 ; B = GND
R632  Q_RES  2.2K 5% CHIP  pkg 0402LF  page 151 : A = PVDD18_S5_P0 ; B = SMB_CPU_5_SCL

(kicad_pcb
	(version 20260206)
	(generator "pcbnew")
	(generator_version "10.0")
	(general
		(thickness 1.6)
		(legacy_teardrops no)
	)
	(paper "A4")
	(title_block
		(title "04192023_DAF0TMB3IC0_F0TG_MB_C_brd_V02_OCP.brd")
		(comment 1 "Grand Teton / footprints 5930-5931 of 8354")
	)
	(layers
		(0 "F.Cu" signal "TOP")
		(4 "In1.Cu" signal "GND")
		(6 "In2.Cu" signal "IN1")
		(8 "In3.Cu" signal "GND1")
		(10 "In4.Cu" signal "IN2")
		(12 "In5.Cu" signal "GND2")
		(14 "In6.Cu" signal "IN3")
		(16 "In7.Cu" signal "GND3")
		(18 "In8.Cu" signal "VCC")
		(20 "In9.Cu" signal "VCC1")
		(22 "In10.Cu" signal "GND4")
		(24 "In11.Cu" signal "IN4")
		(26 "In12.Cu" signal "GND5")
		(28 "In13.Cu" signal "IN5")
		(30 "In14.Cu" signal "GND6")
		(32 "In15.Cu" signal "IN6")
		(34 "In16.Cu" signal "GND7")
		(2 "B.Cu" signal "BOTTOM")
		(9 "F.Adhes" user "F.Adhesive")
		(11 "B.Adhes" user "B.Adhesive")
		(13 "F.Paste" user "Package Geometry/Pastemask Top")
		(15 "B.Paste" user "Package Geometry/Pastemask Bottom")
		(5 "F.SilkS" user "Ref Des/Silkscreen Top")
		(7 "B.SilkS" user "Ref Des/Silkscreen Bottom")
		(1 "F.Mask" user "Board Geometry/Soldermask Top")
		(3 "B.Mask" user "Board Geometry/Soldermask Bottom")
		(17 "Dwgs.User" user "User.Drawings")
		(19 "Cmts.User" user "User.Comments")
		(21 "Eco1.User" user "User.Eco1")
		(23 "Eco2.User" user "User.Eco2")
		(25 "Edge.Cuts" user "Board Geometry/Outline")
		(27 "Margin" user)
		(31 "F.CrtYd" user "Package Geometry/Place Bound Top")
		(29 "B.CrtYd" user "Package Geometry/Place Bound Bottom")
		(35 "F.Fab" user "Ref Des/Assembly Top")
		(33 "B.Fab" user "Ref Des/Assembly Bottom")
	)
	(footprint ""
		(layer "B.Cu")
		(at 190.114428 -140.46454 90)
		(property "Reference" "R632"
			(at 0 0 90)
			(layer "B.SilkS")
			(hide yes)
			(effects
				(font
					(size 1.27 1.27)
				)
				(justify mirror)
			)
		)
		(property "Value" ""
			(at 0 0 90)
			(layer "B.Fab")
			(effects
				(font
					(size 1.27 1.27)
				)
				(justify mirror)
			)
		)
		(duplicate_pad_numbers_are_jumpers no)
		(fp_line
			(start 0.7874 -0.4064)
			(end -0.7874 -0.4064)
			(stroke
				(width 0.1524)
				(type default)
			)
			(layer "B.SilkS")
		)
		(fp_line
			(start -0.7874 -0.4064)
			(end -0.7874 0.4064)
			(stroke
				(width 0.1524)
				(type default)
			)
			(layer "B.SilkS")
		)
		(fp_line
			(start 0.7874 0.4064)
			(end 0.7874 -0.4064)
			(stroke
				(width 0.1524)
				(type default)
			)
			(layer "B.SilkS")
		)
		(fp_line
			(start -0.7874 0.4064)
			(end 0.7874 0.4064)
			(stroke
				(width 0.1524)
				(type default)
			)
			(layer "B.SilkS")
		)
		(fp_line
			(start 0.67945 -0.305054)
			(end 0.12065 -0.305054)
			(stroke
				(width 0.1)
				(type default)
			)
			(layer "B.Fab")
		)
		(fp_line
			(start 0.12065 -0.305054)
			(end 0.12065 -0.2794)
			(stroke
				(width 0.1)
				(type default)
			)
			(layer "B.Fab")
		)
		(fp_line
			(start -0.12065 -0.3048)
			(end -0.67945 -0.3048)
			(stroke
				(width 0.1)
				(type default)
			)
			(layer "B.Fab")
		)
		(fp_line
			(start -0.67945 -0.3048)
			(end -0.67945 0.3048)
			(stroke
				(width 0.1)
				(type default)
			)
			(layer "B.Fab")
		)
		(fp_line
			(start 0.12065 -0.2794)
			(end -0.12065 -0.2794)
			(stroke
				(width 0.1)
				(type default)
			)
			(layer "B.Fab")
		)
		(fp_line
			(start -0.12065 -0.2794)
			(end -0.12065 -0.3048)
			(stroke
				(width 0.1)
				(type default)
			)
			(layer "B.Fab")
		)
		(fp_line
			(start 0.12065 0.2794)
			(end 0.12065 0.3048)
			(stroke
				(width 0.1)
				(type default)
			)
			(layer "B.Fab")
		)
		(fp_line
			(start -0.120396 0.2794)
			(end 0.12065 0.2794)
			(stroke
				(width 0.1)
				(type default)
			)
			(layer "B.Fab")
		)
		(fp_line
			(start 0.67945 0.3048)
			(end 0.67945 -0.305054)
			(stroke
				(width 0.1)
				(type default)
			)
			(layer "B.Fab")
		)
		(fp_line
			(start 0.12065 0.3048)
			(end 0.67945 0.3048)
			(stroke
				(width 0.1)
				(type default)
			)
			(layer "B.Fab")
		)
		(fp_line
			(start -0.120396 0.3048)
			(end -0.120396 0.2794)
			(stroke
				(width 0.1)
				(type default)
			)
			(layer "B.Fab")
		)
		(fp_line
			(start -0.67945 0.3048)
			(end -0.120396 0.3048)
			(stroke
				(width 0.1)
				(type default)
			)
			(layer "B.Fab")
		)
		(pad "1" smd circle
			(at 0.40005 0 270)
			(size 0 0)
			(layers "B.Cu" "B.Mask" "B.Paste")
			(net "PVDD18_S5_P0")
		)
		(pad "2" smd circle
			(at -0.40005 0 270)
			(size 0 0)
			(layers "B.Cu" "B.Mask" "B.Paste")
			(net "SMB_CPU_5_SCL")
		)
	)
	(footprint ""
		(layer "B.Cu")
		(at 110.276386 -267.529564)
		(property "Reference" "C2359"
			(at 0 0 0)
			(layer "B.SilkS")
			(hide yes)
			(effects
				(font
					(size 1.27 1.27)
				)
				(justify mirror)
			)
		)
		(property "Value" ""
			(at 0 0 0)
			(layer "B.Fab")
			(effects
				(font
					(size 1.27 1.27)
				)
				(justify mirror)
			)
		)
		(duplicate_pad_numbers_are_jumpers no)
		(fp_line
			(start -0.7874 -0.4064)
			(end -0.7874 0.4064)
			(stroke
				(width 0.1524)
				(type default)
			)
			(layer "B.SilkS")
		)
		(fp_line
			(start -0.7874 0.4064)
			(end 0.7874 0.4064)
			(stroke
				(width 0.1524)
				(type default)
			)
			(layer "B.SilkS")
		)
		(fp_line
			(start 0.7874 -0.4064)
			(end -0.7874 -0.4064)
			(stroke
				(width 0.1524)
				(type default)
			)
			(layer "B.SilkS")
		)
		(fp_line
			(start 0.7874 0.4064)
			(end 0.7874 -0.4064)
			(stroke
				(width 0.1524)
				(type default)
			)
			(layer "B.SilkS")
		)
		(fp_line
			(start -0.67945 -0.3048)
			(end -0.67945 0.3048)
			(stroke
				(width 0.1)
				(type default)
			)
			(layer "B.Fab")
		)
		(fp_line
			(start -0.67945 0.3048)
			(end -0.120396 0.3048)
			(stroke
				(width 0.1)
				(type default)
			)
			(layer "B.Fab")
		)
		(fp_line
			(start -0.12065 -0.3048)
			(end -0.67945 -0.3048)
			(stroke
				(width 0.1)
				(type default)
			)
			(layer "B.Fab")
		)
		(fp_line
			(start -0.12065 -0.2794)
			(end -0.12065 -0.3048)
			(stroke
				(width 0.1)
				(type default)
			)
			(layer "B.Fab")
		)
		(fp_line
			(start -0.120396 0.2794)
			(end 0.12065 0.2794)
			(stroke
				(width 0.1)
				(type default)
			)
			(layer "B.Fab")
		)
		(fp_line
			(start -0.120396 0.3048)
			(end -0.120396 0.2794)
			(stroke
				(width 0.1)
				(type default)
			)
			(layer "B.Fab")
		)
		(fp_line
			(start 0.12065 -0.305054)
			(end 0.12065 -0.2794)
			(stroke
				(width 0.1)
				(type default)
			)
			(layer "B.Fab")
		)
		(fp_line
			(start 0.12065 -0.2794)
			(end -0.12065 -0.2794)
			(stroke
				(width 0.1)
				(type default)
			)
			(layer "B.Fab")
		)
		(fp_line
			(start 0.12065 0.2794)
			(end 0.12065 0.3048)
			(stroke
				(width 0.1)
				(type default)
			)
			(layer "B.Fab")
		)
		(fp_line
			(start 0.12065 0.3048)
			(end 0.67945 0.3048)
			(stroke
				(width 0.1)
				(type default)
			)
			(layer "B.Fab")
		)
		(fp_line
			(start 0.67945 -0.305054)
			(end 0.12065 -0.305054)
			(stroke
				(width 0.1)
				(type default)
			)
			(layer "B.Fab")
		)
		(fp_line
			(start 0.67945 0.3048)
			(end 0.67945 -0.305054)
			(stroke
				(width 0.1)
				(type default)
			)
			(layer "B.Fab")
		)
		(pad "1" smd circle
			(at 0.40005 0 180)
			(size 0 0)
			(layers "B.Cu" "B.Mask" "B.Paste")
			(net "PVDDCR_CPU1_P1")
		)
		(pad "2" smd circle
			(at -0.40005 0 180)
			(size 0 0)
			(layers "B.Cu" "B.Mask" "B.Paste")
			(net "GND")
		)
	)
)
